(kicad_pcb
	(version 20241229)
	(generator "pcbnew")
	(generator_version "9.0")
	(general
		(thickness 1.6642)
		(legacy_teardrops no)
	)
	(paper "A3")
	(title_block
		(title "PolarFire SoM")
		(date "2025-07-22")
		(rev "1.1.4")
		(company "Antmicro Ltd")
		(comment 1 "www.antmicro.com")
		(comment 9 "footprints 217-220 of 470")
	)
	(layers
		(0 "F.Cu" mixed)
		(4 "In1.Cu" power)
		(6 "In2.Cu" signal)
		(8 "In3.Cu" power)
		(10 "In4.Cu" signal)
		(12 "In5.Cu" power)
		(14 "In6.Cu" power)
		(16 "In7.Cu" signal)
		(18 "In8.Cu" power)
		(20 "In9.Cu" signal)
		(22 "In10.Cu" power)
		(24 "In11.Cu" signal)
		(26 "In12.Cu" signal)
		(2 "B.Cu" mixed)
		(9 "F.Adhes" user "F.Adhesive")
		(11 "B.Adhes" user "B.Adhesive")
		(13 "F.Paste" user)
		(15 "B.Paste" user)
		(5 "F.SilkS" user "F.Silkscreen")
		(7 "B.SilkS" user "B.Silkscreen")
		(1 "F.Mask" user)
		(3 "B.Mask" user)
		(17 "Dwgs.User" user "User.Drawings")
		(19 "Cmts.User" user "User.Comments")
		(21 "Eco1.User" user "User.Eco1")
		(23 "Eco2.User" user "User.Eco2")
		(25 "Edge.Cuts" user)
		(27 "Margin" user)
		(31 "F.CrtYd" user "F.Courtyard")
		(29 "B.CrtYd" user "B.Courtyard")
		(35 "F.Fab" user)
		(33 "B.Fab" user)
	)
	(footprint "antmicro-footprints:C_0402_1005Metric"
		(layer "B.Cu")
		(at 222.35 125.955 90)
		(descr "Capacitor SMD 0402")
		(tags "capacitor SMD 0402")
		(property "Reference" "C82"
			(at -0.795 2.525 90)
			(layer "B.SilkS")
			(effects
				(font
					(size 0.7 0.7)
					(thickness 0.15)
				)
				(justify right bottom mirror)
			)
		)
		(property "Value" "C_100n_0402"
			(at -1.022927 -2.155213 90)
			(layer "B.Fab")
			(hide yes)
			(effects
				(font
					(size 0.7 0.7)
					(thickness 0.15)
				)
				(justify right bottom mirror)
			)
		)
		(property "Datasheet" "https://www.murata.com/products/productdetail?partno=GRM155R61H104KE14%23"
			(at 0 0 90)
			(layer "F.Fab")
			(hide yes)
			(effects
				(font
					(size 1.27 1.27)
					(thickness 0.15)
				)
			)
		)
		(property "Description" "SMD Multilayer Ceramic Capacitor, 0.1 µF, 50 V, 0402 [1005 Metric], ± 10%, X5R, GRM Series"
			(at 0 0 90)
			(layer "F.Fab")
			(hide yes)
			(effects
				(font
					(size 1.27 1.27)
					(thickness 0.15)
				)
			)
		)
		(property "Author" "Antmicro"
			(at 348.305 -96.395 0)
			(layer "B.Fab")
			(hide yes)
			(effects
				(font
					(size 1 1)
					(thickness 0.15)
				)
				(justify mirror)
			)
		)
		(property "Dielectric" "X5R"
			(at 348.305 -96.395 0)
			(layer "B.Fab")
			(hide yes)
			(effects
				(font
					(size 1 1)
					(thickness 0.15)
				)
				(justify mirror)
			)
		)
		(property "License" "Apache-2.0"
			(at 348.305 -96.395 0)
			(layer "B.Fab")
			(hide yes)
			(effects
				(font
					(size 1 1)
					(thickness 0.15)
				)
				(justify mirror)
			)
		)
		(property "MPN" "GRM155R61H104KE14D"
			(at 348.305 -96.395 0)
			(layer "B.Fab")
			(hide yes)
			(effects
				(font
					(size 1 1)
					(thickness 0.15)
				)
				(justify mirror)
			)
		)
		(property "Manufacturer" "Murata"
			(at 348.305 -96.395 0)
			(layer "B.Fab")
			(hide yes)
			(effects
				(font
					(size 1 1)
					(thickness 0.15)
				)
				(justify mirror)
			)
		)
		(property "Public" ""
			(at 348.305 -96.395 0)
			(layer "B.Fab")
			(hide yes)
			(effects
				(font
					(size 1 1)
					(thickness 0.15)
				)
				(justify mirror)
			)
		)
		(property "Val" "100n"
			(at 348.305 -96.395 0)
			(layer "B.Fab")
			(hide yes)
			(effects
				(font
					(size 1 1)
					(thickness 0.15)
				)
				(justify mirror)
			)
		)
		(property "Voltage" "50V"
			(at 348.305 -96.395 0)
			(layer "B.Fab")
			(hide yes)
			(effects
				(font
					(size 1 1)
					(thickness 0.15)
				)
				(justify mirror)
			)
		)
		(sheetname "/FPGA Config/")
		(sheetfile "fpga-config.kicad_sch")
		(attr smd)
		(fp_rect
			(start -0.925 0.47)
			(end 0.925 -0.47)
			(stroke
				(width 0.05)
				(type default)
			)
			(fill no)
			(layer "B.CrtYd")
		)
		(fp_line
			(start 0.504 -0.248)
			(end -0.494 -0.248)
			(stroke
				(width 0.15)
				(type solid)
			)
			(layer "B.Fab")
		)
		(fp_line
			(start -0.494 -0.248)
			(end -0.494 0.25)
			(stroke
				(width 0.15)
				(type solid)
			)
			(layer "B.Fab")
		)
		(fp_line
			(start 0.504 0.25)
			(end 0.504 -0.248)
			(stroke
				(width 0.15)
				(type solid)
			)
			(layer "B.Fab")
		)
		(fp_line
			(start -0.494 0.25)
			(end 0.504 0.25)
			(stroke
				(width 0.15)
				(type solid)
			)
			(layer "B.Fab")
		)
		(fp_text user "${REFERENCE}"
			(at -0.939 -4.599 270)
			(layer "B.Fab")
			(effects
				(font
					(size 0.7 0.7)
					(thickness 0.15)
				)
				(justify left bottom mirror)
			)
		)
		(fp_text user "Author: Antmicro"
			(at -0.939 -3.399 270)
			(layer "B.Fab")
			(effects
				(font
					(size 0.7 0.7)
					(thickness 0.15)
				)
				(justify left bottom mirror)
			)
		)
		(fp_text user "License: Apache-2.0"
			(at -0.939 -5.799 270)
			(layer "B.Fab")
			(effects
				(font
					(size 0.7 0.7)
					(thickness 0.15)
				)
				(justify left bottom mirror)
			)
		)
		(pad "1" smd roundrect
			(at -0.48 0 90)
			(size 0.59 0.64)
			(layers "B.Cu" "B.Mask" "B.Paste")
			(roundrect_rratio 0.25)
			(net 417 "GND")
			(pintype "passive")
		)
		(pad "2" smd roundrect
			(at 0.48 0 90)
			(size 0.59 0.64)
			(layers "B.Cu" "B.Mask" "B.Paste")
			(roundrect_rratio 0.25)
			(net 50 "+3V3")
			(pintype "passive")
		)
	)
	(footprint "antmicro-footprints:R_0603_1608Metric"
		(layer "B.Cu")
		(at 186.4 147.7 90)
		(descr "Resistor SMD 0603")
		(tags "resistor SMD 0603")
		(property "Reference" "R20"
			(at 0 1.6 270)
			(layer "B.SilkS")
			(effects
				(font
					(size 0.7 0.7)
					(thickness 0.15)
				)
				(justify left bottom mirror)
			)
		)
		(property "Value" "R_0R_22.4A_0603"
			(at 0 -1.6 270)
			(layer "B.Fab")
			(hide yes)
			(effects
				(font
					(size 0.7 0.7)
					(thickness 0.15)
				)
				(justify left bottom mirror)
			)
		)
		(property "Datasheet" "https://fscdn.rohm.com/en/products/databook/datasheet/passive/resistor/chip_resistor/pmr-jpw-e.pdf"
			(at 0 0 90)
			(layer "F.Fab")
			(hide yes)
			(effects
				(font
					(size 1.27 1.27)
					(thickness 0.15)
				)
			)
		)
		(property "Description" "SMD Chip Resistor"
			(at 0 0 90)
			(layer "F.Fab")
			(hide yes)
			(effects
				(font
					(size 1.27 1.27)
					(thickness 0.15)
				)
			)
		)
		(property "Author" "Antmicro"
			(at 334.1 -38.7 0)
			(layer "B.Fab")
			(hide yes)
			(effects
				(font
					(size 1 1)
					(thickness 0.15)
				)
				(justify mirror)
			)
		)
		(property "License" "Apache-2.0"
			(at 334.1 -38.7 0)
			(layer "B.Fab")
			(hide yes)
			(effects
				(font
					(size 1 1)
					(thickness 0.15)
				)
				(justify mirror)
			)
		)
		(property "MPN" "PMR03EZPJ000"
			(at 334.1 -38.7 0)
			(layer "B.Fab")
			(hide yes)
			(effects
				(font
					(size 1 1)
					(thickness 0.15)
				)
				(justify mirror)
			)
		)
		(property "Manufacturer" "ROHM Semiconductor"
			(at 334.1 -38.7 0)
			(layer "B.Fab")
			(hide yes)
			(effects
				(font
					(size 1 1)
					(thickness 0.15)
				)
				(justify mirror)
			)
		)
		(property "Max. Curr." "22.4A"
			(at 334.1 -38.7 0)
			(layer "B.Fab")
			(hide yes)
			(effects
				(font
					(size 1 1)
					(thickness 0.15)
				)
				(justify mirror)
			)
		)
		(property "Public" ""
			(at 334.1 -38.7 0)
			(layer "B.Fab")
			(hide yes)
			(effects
				(font
					(size 1 1)
					(thickness 0.15)
				)
				(justify mirror)
			)
		)
		(property "Tolerance" "template_tolerance"
			(at 334.1 -38.7 0)
			(layer "B.Fab")
			(hide yes)
			(effects
				(font
					(size 1 1)
					(thickness 0.15)
				)
				(justify mirror)
			)
		)
		(property "Val" "0R"
			(at 334.1 -38.7 0)
			(layer "B.Fab")
			(hide yes)
			(effects
				(font
					(size 1 1)
					(thickness 0.15)
				)
				(justify mirror)
			)
		)
		(sheetname "/Supply/")
		(sheetfile "supply.kicad_sch")
		(attr smd)
		(fp_line
			(start -0.15 -0.4)
			(end 0.15 -0.4)
			(stroke
				(width 0.15)
				(type solid)
			)
			(layer "B.SilkS")
		)
		(fp_line
			(start -0.15 0.4)
			(end 0.15 0.4)
			(stroke
				(width 0.15)
				(type solid)
			)
			(layer "B.SilkS")
		)
		(fp_rect
			(start -1.25 0.65)
			(end 1.25 -0.65)
			(stroke
				(width 0.05)
				(type solid)
			)
			(fill no)
			(layer "B.CrtYd")
		)
		(fp_rect
			(start -0.8 0.4)
			(end 0.8 -0.4)
			(stroke
				(width 0.15)
				(type solid)
			)
			(fill no)
			(layer "B.Fab")
		)
		(fp_text user "Author: Antmicro"
			(at -1.25 -4.9 270)
			(layer "B.Fab")
			(effects
				(font
					(size 0.7 0.7)
					(thickness 0.15)
				)
				(justify left bottom mirror)
			)
		)
		(fp_text user "License: Apache-2.0"
			(at -1.25 -5.9 270)
			(layer "B.Fab")
			(effects
				(font
					(size 0.7 0.7)
					(thickness 0.15)
				)
				(justify left bottom mirror)
			)
		)
		(fp_text user "${REFERENCE}"
			(at -1.25 -3.898 270)
			(layer "B.Fab")
			(effects
				(font
					(size 0.7 0.7)
					(thickness 0.15)
				)
				(justify left bottom mirror)
			)
		)
		(pad "1" smd roundrect
			(at -0.7 0 90)
			(size 0.8 1)
			(layers "B.Cu" "B.Mask" "B.Paste")
			(roundrect_rratio 0.2)
			(net 522 "/Supply/1V05_REG")
			(pintype "passive")
		)
		(pad "2" smd roundrect
			(at 0.7 0 90)
			(size 0.8 1)
			(layers "B.Cu" "B.Mask" "B.Paste")
			(roundrect_rratio 0.2)
			(net 47 "+1V05")
			(pintype "passive")
		)
	)
	(footprint "antmicro-footprints:C_0402_1005Metric"
		(layer "B.Cu")
		(at 175.248 132.7165 90)
		(descr "Capacitor SMD 0402")
		(tags "capacitor SMD 0402")
		(property "Reference" "C129"
			(at -0.9235 2.312 315)
			(layer "B.SilkS")
			(effects
				(font
					(size 0.7 0.7)
					(thickness 0.15)
				)
				(justify left bottom mirror)
			)
		)
		(property "Value" "C_1u_0402"
			(at -1.022927 -2.155213 270)
			(layer "B.Fab")
			(hide yes)
			(effects
				(font
					(size 0.7 0.7)
					(thickness 0.15)
				)
				(justify left bottom mirror)
			)
		)
		(property "Datasheet" "https://product.tdk.com/en/search/capacitor/ceramic/mlcc/info?part_no=C1005X6S1A105K050BC"
			(at 0 0 90)
			(layer "F.Fab")
			(hide yes)
			(effects
				(font
					(size 1.27 1.27)
					(thickness 0.15)
				)
			)
		)
		(property "Description" "SMD Multilayer Ceramic Capacitor, 1 µF, 10 V, 0402 [1005 Metric], ± 10%, X6S, C"
			(at 0 0 90)
			(layer "F.Fab")
			(hide yes)
			(effects
				(font
					(size 1.27 1.27)
					(thickness 0.15)
				)
			)
		)
		(property "Author" "Antmicro"
			(at 307.9645 -42.5315 0)
			(layer "B.Fab")
			(hide yes)
			(effects
				(font
					(size 1 1)
					(thickness 0.15)
				)
				(justify mirror)
			)
		)
		(property "Dielectric" "X5R"
			(at 307.9645 -42.5315 0)
			(layer "B.Fab")
			(hide yes)
			(effects
				(font
					(size 1 1)
					(thickness 0.15)
				)
				(justify mirror)
			)
		)
		(property "License" "Apache-2.0"
			(at 307.9645 -42.5315 0)
			(layer "B.Fab")
			(hide yes)
			(effects
				(font
					(size 1 1)
					(thickness 0.15)
				)
				(justify mirror)
			)
		)
		(property "MPN" "C1005X6S1A105K050BC"
			(at 307.9645 -42.5315 0)
			(layer "B.Fab")
			(hide yes)
			(effects
				(font
					(size 1 1)
					(thickness 0.15)
				)
				(justify mirror)
			)
		)
		(property "Manufacturer" "TDK"
			(at 307.9645 -42.5315 0)
			(layer "B.Fab")
			(hide yes)
			(effects
				(font
					(size 1 1)
					(thickness 0.15)
				)
				(justify mirror)
			)
		)
		(property "Public" ""
			(at 307.9645 -42.5315 0)
			(layer "B.Fab")
			(hide yes)
			(effects
				(font
					(size 1 1)
					(thickness 0.15)
				)
				(justify mirror)
			)
		)
		(property "Val" "1u"
			(at 307.9645 -42.5315 0)
			(layer "B.Fab")
			(hide yes)
			(effects
				(font
					(size 1 1)
					(thickness 0.15)
				)
				(justify mirror)
			)
		)
		(property "Voltage" "16V"
			(at 307.9645 -42.5315 0)
			(layer "B.Fab")
			(hide yes)
			(effects
				(font
					(size 1 1)
					(thickness 0.15)
				)
				(justify mirror)
			)
		)
		(sheetname "/LPDDR4/")
		(sheetfile "lpddr.kicad_sch")
		(attr smd)
		(fp_rect
			(start -0.925 0.47)
			(end 0.925 -0.47)
			(stroke
				(width 0.05)
				(type default)
			)
			(fill no)
			(layer "B.CrtYd")
		)
		(fp_line
			(start 0.504 -0.248)
			(end -0.494 -0.248)
			(stroke
				(width 0.15)
				(type solid)
			)
			(layer "B.Fab")
		)
		(fp_line
			(start -0.494 -0.248)
			(end -0.494 0.25)
			(stroke
				(width 0.15)
				(type solid)
			)
			(layer "B.Fab")
		)
		(fp_line
			(start 0.504 0.25)
			(end 0.504 -0.248)
			(stroke
				(width 0.15)
				(type solid)
			)
			(layer "B.Fab")
		)
		(fp_line
			(start -0.494 0.25)
			(end 0.504 0.25)
			(stroke
				(width 0.15)
				(type solid)
			)
			(layer "B.Fab")
		)
		(fp_text user "License: Apache-2.0"
			(at -0.939 -5.799 270)
			(layer "B.Fab")
			(effects
				(font
					(size 0.7 0.7)
					(thickness 0.15)
				)
				(justify left bottom mirror)
			)
		)
		(fp_text user "Author: Antmicro"
			(at -0.939 -3.399 270)
			(layer "B.Fab")
			(effects
				(font
					(size 0.7 0.7)
					(thickness 0.15)
				)
				(justify left bottom mirror)
			)
		)
		(fp_text user "${REFERENCE}"
			(at -0.939 -4.599 270)
			(layer "B.Fab")
			(effects
				(font
					(size 0.7 0.7)
					(thickness 0.15)
				)
				(justify left bottom mirror)
			)
		)
		(pad "1" smd roundrect
			(at -0.48 0 90)
			(size 0.59 0.64)
			(layers "B.Cu" "B.Mask" "B.Paste")
			(roundrect_rratio 0.25)
			(net 417 "GND")
			(pintype "passive")
		)
		(pad "2" smd roundrect
			(at 0.48 0 90)
			(size 0.59 0.64)
			(layers "B.Cu" "B.Mask" "B.Paste")
			(roundrect_rratio 0.25)
			(net 2 "+1V1")
			(pintype "passive")
		)
	)
	(footprint "antmicro-footprints:R_0402_1005Metric"
		(layer "B.Cu")
		(at 186.475 154.425 90)
		(descr "Resistor SMD 0402")
		(tags "resistor SMD 0402")
		(property "Reference" "R63"
			(at 1.225 -5.125 270)
			(layer "B.SilkS")
			(effects
				(font
					(size 0.7 0.7)
					(thickness 0.15)
				)
				(justify left bottom mirror)
			)
		)
		(property "Value" "R_100k_0402"
			(at -1.011843 -1.772047 270)
			(layer "B.Fab")
			(hide yes)
			(effects
				(font
					(size 0.7 0.7)
					(thickness 0.15)
				)
				(justify left bottom mirror)
			)
		)
		(property "Datasheet" "https://www.bourns.com/docs/product-datasheets/cr.pdf"
			(at 0 0 90)
			(layer "F.Fab")
			(hide yes)
			(effects
				(font
					(size 1.27 1.27)
					(thickness 0.15)
				)
			)
		)
		(property "Description" "SMD Chip Resistor, 100 kohm, ± 1%, 62.5 mW, 0402 [1005 Metric], Thick Film, General Purpose"
			(at 0 0 90)
			(layer "F.Fab")
			(hide yes)
			(effects
				(font
					(size 1.27 1.27)
					(thickness 0.15)
				)
			)
		)
		(property "Author" "Antmicro"
			(at 340.9 -32.05 0)
			(layer "B.Fab")
			(hide yes)
			(effects
				(font
					(size 1 1)
					(thickness 0.15)
				)
				(justify mirror)
			)
		)
		(property "License" "Apache-2.0"
			(at 340.9 -32.05 0)
			(layer "B.Fab")
			(hide yes)
			(effects
				(font
					(size 1 1)
					(thickness 0.15)
				)
				(justify mirror)
			)
		)
		(property "MPN" "CR0402-FX-1003GLF"
			(at 340.9 -32.05 0)
			(layer "B.Fab")
			(hide yes)
			(effects
				(font
					(size 1 1)
					(thickness 0.15)
				)
				(justify mirror)
			)
		)
		(property "Manufacturer" "Bourns"
			(at 340.9 -32.05 0)
			(layer "B.Fab")
			(hide yes)
			(effects
				(font
					(size 1 1)
					(thickness 0.15)
				)
				(justify mirror)
			)
		)
		(property "Public" ""
			(at 340.9 -32.05 0)
			(layer "B.Fab")
			(hide yes)
			(effects
				(font
					(size 1 1)
					(thickness 0.15)
				)
				(justify mirror)
			)
		)
		(property "Tolerance" "1%"
			(at 340.9 -32.05 0)
			(layer "B.Fab")
			(hide yes)
			(effects
				(font
					(size 1 1)
					(thickness 0.15)
				)
				(justify mirror)
			)
		)
		(property "Val" "100k"
			(at 340.9 -32.05 0)
			(layer "B.Fab")
			(hide yes)
			(effects
				(font
					(size 1 1)
					(thickness 0.15)
				)
				(justify mirror)
			)
		)
		(sheetname "/Bottom Connector/")
		(sheetfile "bottom-connector.kicad_sch")
		(attr smd)
		(fp_rect
			(start -0.925 0.47)
			(end 0.925 -0.47)
			(stroke
				(width 0.05)
				(type default)
			)
			(fill no)
			(layer "B.CrtYd")
		)
		(fp_rect
			(start -0.5 0.25)
			(end 0.5 -0.25)
			(stroke
				(width 0.15)
				(type solid)
			)
			(fill no)
			(layer "B.Fab")
		)
		(fp_text user "License: Apache-2.0"
			(at -0.95 -5.169 270)
			(layer "B.Fab")
			(effects
				(font
					(size 0.7 0.7)
					(thickness 0.15)
				)
				(justify left bottom mirror)
			)
		)
		(fp_text user "Author: Antmicro"
			(at -0.95 -4.169 270)
			(layer "B.Fab")
			(effects
				(font
					(size 0.7 0.7)
					(thickness 0.15)
				)
				(justify left bottom mirror)
			)
		)
		(fp_text user "${REFERENCE}"
			(at -0.95 -3.168 270)
			(layer "B.Fab")
			(effects
				(font
					(size 0.7 0.7)
					(thickness 0.15)
				)
				(justify left bottom mirror)
			)
		)
		(pad "1" smd roundrect
			(at -0.48 0 90)
			(size 0.59 0.64)
			(layers "B.Cu" "B.Mask" "B.Paste")
			(roundrect_rratio 0.25)
			(net 417 "GND")
			(pintype "passive")
		)
		(pad "2" smd roundrect
			(at 0.48 0 90)
			(size 0.59 0.64)
			(layers "B.Cu" "B.Mask" "B.Paste")
			(roundrect_rratio 0.25)
			(net 275 "Net-(Q3-REF)")
			(pintype "passive")
		)
	)
)
